# T6G (Grand Teton) — schematic netlist excerpt (pin names and nets, part order shuffled) for the footprints in the layout excerpt that follows; sources: Cadence DE-HDL packaged netlist, KiCad conversion of 04192023_DAF0TMB3IC0_F0TG_MB_C_brd_V02_OCP.brd

R4519  Q_RES  10K 1% CHIP  pkg 0402LF  page 182 : A = FM_9ZXL045_P0_1_OE_N ; B = GND
R284  Q_RES  0 5% CHIP  pkg 0402LF  page 82 : A = FM_PVDDCR_CPU0_P1_OCP_N ; B = PVDDCR_CPU0_P1_OCP_N

(kicad_pcb
	(version 20260206)
	(generator "pcbnew")
	(generator_version "10.0")
	(general
		(thickness 1.6)
		(legacy_teardrops no)
	)
	(paper "A4")
	(title_block
		(title "04192023_DAF0TMB3IC0_F0TG_MB_C_brd_V02_OCP.brd")
		(comment 1 "Grand Teton / footprints 334-335 of 8354")
	)
	(layers
		(0 "F.Cu" signal "TOP")
		(4 "In1.Cu" signal "GND")
		(6 "In2.Cu" signal "IN1")
		(8 "In3.Cu" signal "GND1")
		(10 "In4.Cu" signal "IN2")
		(12 "In5.Cu" signal "GND2")
		(14 "In6.Cu" signal "IN3")
		(16 "In7.Cu" signal "GND3")
		(18 "In8.Cu" signal "VCC")
		(20 "In9.Cu" signal "VCC1")
		(22 "In10.Cu" signal "GND4")
		(24 "In11.Cu" signal "IN4")
		(26 "In12.Cu" signal "GND5")
		(28 "In13.Cu" signal "IN5")
		(30 "In14.Cu" signal "GND6")
		(32 "In15.Cu" signal "IN6")
		(34 "In16.Cu" signal "GND7")
		(2 "B.Cu" signal "BOTTOM")
		(9 "F.Adhes" user "F.Adhesive")
		(11 "B.Adhes" user "B.Adhesive")
		(13 "F.Paste" user "Package Geometry/Pastemask Top")
		(15 "B.Paste" user "Package Geometry/Pastemask Bottom")
		(5 "F.SilkS" user "Ref Des/Silkscreen Top")
		(7 "B.SilkS" user "Ref Des/Silkscreen Bottom")
		(1 "F.Mask" user "Board Geometry/Soldermask Top")
		(3 "B.Mask" user "Board Geometry/Soldermask Bottom")
		(17 "Dwgs.User" user "User.Drawings")
		(19 "Cmts.User" user "User.Comments")
		(21 "Eco1.User" user "User.Eco1")
		(23 "Eco2.User" user "User.Eco2")
		(25 "Edge.Cuts" user "Board Geometry/Outline")
		(27 "Margin" user)
		(31 "F.CrtYd" user "Package Geometry/Place Bound Top")
		(29 "B.CrtYd" user "Package Geometry/Place Bound Bottom")
		(35 "F.Fab" user "Ref Des/Assembly Top")
		(33 "B.Fab" user "Ref Des/Assembly Bottom")
	)
	(footprint ""
		(layer "F.Cu")
		(at 288.568638 -412.741872 -90)
		(property "Reference" "R4519"
			(at 0 0 270)
			(layer "F.SilkS")
			(hide yes)
			(effects
				(font
					(size 1.27 1.27)
				)
			)
		)
		(property "Value" ""
			(at 0 0 270)
			(layer "F.Fab")
			(effects
				(font
					(size 1.27 1.27)
				)
			)
		)
		(duplicate_pad_numbers_are_jumpers no)
		(fp_line
			(start -0.7874 0.4064)
			(end -0.7874 -0.4064)
			(stroke
				(width 0.1524)
				(type default)
			)
			(layer "F.SilkS")
		)
		(fp_line
			(start 0.7874 0.4064)
			(end -0.7874 0.4064)
			(stroke
				(width 0.1524)
				(type default)
			)
			(layer "F.SilkS")
		)
		(fp_line
			(start -0.7874 -0.4064)
			(end 0.7874 -0.4064)
			(stroke
				(width 0.1524)
				(type default)
			)
			(layer "F.SilkS")
		)
		(fp_line
			(start 0.7874 -0.4064)
			(end 0.7874 0.4064)
			(stroke
				(width 0.1524)
				(type default)
			)
			(layer "F.SilkS")
		)
		(fp_line
			(start -0.67945 0.3048)
			(end -0.67945 -0.305054)
			(stroke
				(width 0.1)
				(type default)
			)
			(layer "F.Fab")
		)
		(fp_line
			(start -0.12065 0.3048)
			(end -0.67945 0.3048)
			(stroke
				(width 0.1)
				(type default)
			)
			(layer "F.Fab")
		)
		(fp_line
			(start 0.120396 0.3048)
			(end 0.120396 0.2794)
			(stroke
				(width 0.1)
				(type default)
			)
			(layer "F.Fab")
		)
		(fp_line
			(start 0.67945 0.3048)
			(end 0.120396 0.3048)
			(stroke
				(width 0.1)
				(type default)
			)
			(layer "F.Fab")
		)
		(fp_line
			(start -0.12065 0.2794)
			(end -0.12065 0.3048)
			(stroke
				(width 0.1)
				(type default)
			)
			(layer "F.Fab")
		)
		(fp_line
			(start 0.120396 0.2794)
			(end -0.12065 0.2794)
			(stroke
				(width 0.1)
				(type default)
			)
			(layer "F.Fab")
		)
		(fp_line
			(start -0.12065 -0.2794)
			(end 0.12065 -0.2794)
			(stroke
				(width 0.1)
				(type default)
			)
			(layer "F.Fab")
		)
		(fp_line
			(start 0.12065 -0.2794)
			(end 0.12065 -0.3048)
			(stroke
				(width 0.1)
				(type default)
			)
			(layer "F.Fab")
		)
		(fp_line
			(start 0.12065 -0.3048)
			(end 0.67945 -0.3048)
			(stroke
				(width 0.1)
				(type default)
			)
			(layer "F.Fab")
		)
		(fp_line
			(start 0.67945 -0.3048)
			(end 0.67945 0.3048)
			(stroke
				(width 0.1)
				(type default)
			)
			(layer "F.Fab")
		)
		(fp_line
			(start -0.67945 -0.305054)
			(end -0.12065 -0.305054)
			(stroke
				(width 0.1)
				(type default)
			)
			(layer "F.Fab")
		)
		(fp_line
			(start -0.12065 -0.305054)
			(end -0.12065 -0.2794)
			(stroke
				(width 0.1)
				(type default)
			)
			(layer "F.Fab")
		)
		(pad "1" smd circle
			(at -0.40005 0 270)
			(size 0 0)
			(layers "F.Cu" "F.Mask" "F.Paste")
			(net "FM_9ZXL045_P0_1_OE_N")
		)
		(pad "2" smd circle
			(at 0.40005 0 270)
			(size 0 0)
			(layers "F.Cu" "F.Mask" "F.Paste")
			(net "GND")
		)
	)
	(footprint ""
		(layer "F.Cu")
		(at 182.753 -100.294948 -90)
		(property "Reference" "R284"
			(at 0 0 270)
			(layer "F.SilkS")
			(hide yes)
			(effects
				(font
					(size 1.27 1.27)
				)
			)
		)
		(property "Value" ""
			(at 0 0 270)
			(layer "F.Fab")
			(effects
				(font
					(size 1.27 1.27)
				)
			)
		)
		(duplicate_pad_numbers_are_jumpers no)
		(fp_line
			(start -0.7874 0.4064)
			(end -0.7874 -0.4064)
			(stroke
				(width 0.1524)
				(type default)
			)
			(layer "F.SilkS")
		)
		(fp_line
			(start 0.7874 0.4064)
			(end -0.7874 0.4064)
			(stroke
				(width 0.1524)
				(type default)
			)
			(layer "F.SilkS")
		)
		(fp_line
			(start -0.7874 -0.4064)
			(end 0.7874 -0.4064)
			(stroke
				(width 0.1524)
				(type default)
			)
			(layer "F.SilkS")
		)
		(fp_line
			(start 0.7874 -0.4064)
			(end 0.7874 0.4064)
			(stroke
				(width 0.1524)
				(type default)
			)
			(layer "F.SilkS")
		)
		(fp_line
			(start -0.67945 0.3048)
			(end -0.67945 -0.305054)
			(stroke
				(width 0.1)
				(type default)
			)
			(layer "F.Fab")
		)
		(fp_line
			(start -0.12065 0.3048)
			(end -0.67945 0.3048)
			(stroke
				(width 0.1)
				(type default)
			)
			(layer "F.Fab")
		)
		(fp_line
			(start 0.120396 0.3048)
			(end 0.120396 0.2794)
			(stroke
				(width 0.1)
				(type default)
			)
			(layer "F.Fab")
		)
		(fp_line
			(start 0.67945 0.3048)
			(end 0.120396 0.3048)
			(stroke
				(width 0.1)
				(type default)
			)
			(layer "F.Fab")
		)
		(fp_line
			(start -0.12065 0.2794)
			(end -0.12065 0.3048)
			(stroke
				(width 0.1)
				(type default)
			)
			(layer "F.Fab")
		)
		(fp_line
			(start 0.120396 0.2794)
			(end -0.12065 0.2794)
			(stroke
				(width 0.1)
				(type default)
			)
			(layer "F.Fab")
		)
		(fp_line
			(start -0.12065 -0.2794)
			(end 0.12065 -0.2794)
			(stroke
				(width 0.1)
				(type default)
			)
			(layer "F.Fab")
		)
		(fp_line
			(start 0.12065 -0.2794)
			(end 0.12065 -0.3048)
			(stroke
				(width 0.1)
				(type default)
			)
			(layer "F.Fab")
		)
		(fp_line
			(start 0.12065 -0.3048)
			(end 0.67945 -0.3048)
			(stroke
				(width 0.1)
				(type default)
			)
			(layer "F.Fab")
		)
		(fp_line
			(start 0.67945 -0.3048)
			(end 0.67945 0.3048)
			(stroke
				(width 0.1)
				(type default)
			)
			(layer "F.Fab")
		)
		(fp_line
			(start -0.67945 -0.305054)
			(end -0.12065 -0.305054)
			(stroke
				(width 0.1)
				(type default)
			)
			(layer "F.Fab")
		)
		(fp_line
			(start -0.12065 -0.305054)
			(end -0.12065 -0.2794)
			(stroke
				(width 0.1)
				(type default)
			)
			(layer "F.Fab")
		)
		(pad "1" smd circle
			(at -0.40005 0 270)
			(size 0 0)
			(layers "F.Cu" "F.Mask" "F.Paste")
			(net "FM_PVDDCR_CPU0_P1_OCP_N")
		)
		(pad "2" smd circle
			(at 0.40005 0 270)
			(size 0 0)
			(layers "F.Cu" "F.Mask" "F.Paste")
			(net "PVDDCR_CPU0_P1_OCP_N")
		)
	)
)
